# BASEBOARD_FAB2 (Tioga Pass) — schematic netlist excerpt (pin names and nets, part order shuffled) for the footprints in the layout excerpt that follows; sources: Cadence DE-HDL packaged netlist, KiCad conversion of Wiwynn_Tioga_Pass_MB.brd

C8A9  CAP  1000PF 50V 10% X7R  pkg 0402LF  page 235 : A = PWRGD_PVNN_PCH_R ; B = GND
C7G9  CAP  0.22UF 16V 10% X7R  pkg 0402  page 105 : A = P3E_CPU0_PE2_SS_TXP<13> ; B = P3E_CPU0_PE2_SS_C_TXP<13>
C5D23  CAP_A  22.0UF 4V 20% X6S  pkg 0603V  page 42 : A = PVCCMCP_CPU0 ; B = GND

(kicad_pcb
	(version 20260206)
	(generator "pcbnew")
	(generator_version "10.0")
	(general
		(thickness 1.6)
		(legacy_teardrops no)
	)
	(paper "A4")
	(title_block
		(title "Wiwynn_Tioga_Pass_MB.brd")
		(comment 1 "Tioga Pass / footprints 179-181 of 4770")
	)
	(layers
		(0 "F.Cu" signal "TOP")
		(4 "In1.Cu" signal "L2GND")
		(6 "In2.Cu" signal "L3")
		(8 "In3.Cu" signal "L4GND")
		(10 "In4.Cu" signal "L5")
		(12 "In5.Cu" signal "L6GND")
		(14 "In6.Cu" signal "L7VCC")
		(16 "In7.Cu" signal "L8VCC")
		(18 "In8.Cu" signal "L9GND")
		(20 "In9.Cu" signal "L10")
		(22 "In10.Cu" signal "L11GND")
		(24 "In11.Cu" signal "L12")
		(26 "In12.Cu" signal "L13GND")
		(2 "B.Cu" signal "BOTTOM")
		(9 "F.Adhes" user "F.Adhesive")
		(11 "B.Adhes" user "B.Adhesive")
		(13 "F.Paste" user "Package Geometry/Pastemask Top")
		(15 "B.Paste" user "Package Geometry/Pastemask Bottom")
		(5 "F.SilkS" user "Ref Des/Silkscreen Top")
		(7 "B.SilkS" user "Ref Des/Silkscreen Bottom")
		(1 "F.Mask" user "Board Geometry/Soldermask Top")
		(3 "B.Mask" user "Board Geometry/Soldermask Bottom")
		(17 "Dwgs.User" user "User.Drawings")
		(19 "Cmts.User" user "User.Comments")
		(21 "Eco1.User" user "User.Eco1")
		(23 "Eco2.User" user "User.Eco2")
		(25 "Edge.Cuts" user "Board Geometry/Outline")
		(27 "Margin" user)
		(31 "F.CrtYd" user "Package Geometry/Place Bound Top")
		(29 "B.CrtYd" user "Package Geometry/Place Bound Bottom")
		(35 "F.Fab" user "Ref Des/Assembly Top")
		(33 "B.Fab" user "Ref Des/Assembly Bottom")
	)
	(footprint ""
		(layer "F.Cu")
		(at 367.077244 -10.916158)
		(property "Reference" "C7G9"
			(at 0 0 0)
			(layer "F.SilkS")
			(hide yes)
			(effects
				(font
					(size 1.27 1.27)
				)
			)
		)
		(property "Value" ""
			(at 0 0 0)
			(layer "F.Fab")
			(effects
				(font
					(size 1.27 1.27)
				)
			)
		)
		(duplicate_pad_numbers_are_jumpers no)
		(fp_rect
			(start -0.3048 0.9906)
			(end 0.3048 -0.1016)
			(stroke
				(width 0)
				(type default)
			)
			(fill no)
			(layer "F.CrtYd")
		)
		(fp_line
			(start -0.3048 -0.1016)
			(end -0.3048 0.9906)
			(stroke
				(width 0.1)
				(type default)
			)
			(layer "F.Fab")
		)
		(fp_line
			(start -0.3048 0.9906)
			(end 0.3048 0.9906)
			(stroke
				(width 0.1)
				(type default)
			)
			(layer "F.Fab")
		)
		(fp_line
			(start 0.3048 -0.1016)
			(end -0.3048 -0.1016)
			(stroke
				(width 0.1)
				(type default)
			)
			(layer "F.Fab")
		)
		(fp_line
			(start 0.3048 0.9906)
			(end 0.3048 -0.1016)
			(stroke
				(width 0.1)
				(type default)
			)
			(layer "F.Fab")
		)
		(pad "1" smd rect
			(at 0 0)
			(size 0.508 0.508)
			(layers "F.Cu" "F.Mask" "F.Paste")
			(net "P3E_CPU0_PE2_SS_TXP<13>")
		)
		(pad "2" smd rect
			(at 0 0.889)
			(size 0.508 0.508)
			(layers "F.Cu" "F.Mask" "F.Paste")
			(net "P3E_CPU0_PE2_SS_C_TXP<13>")
		)
		(zone
			(layer "F.Cu")
			(hatch none 0.5)
			(connect_pads
				(clearance 0)
			)
			(min_thickness 0.25)
			(keepout
				(tracks allowed)
				(vias not_allowed)
				(pads allowed)
				(copperpour not_allowed)
				(footprints allowed)
			)
			(placement
				(enabled no)
				(sheetname "")
			)
			(fill
				(thermal_gap 0.5)
				(thermal_bridge_width 0.5)
				(island_removal_mode 0)
			)
			(polygon
				(pts
					(xy 366.823244 -10.281158) (xy 367.331244 -10.281158) (xy 367.331244 -10.662158) (xy 366.823244 -10.662158)
				)
			)
		)
		(zone
			(layer "F.Cu")
			(hatch none 0.5)
			(connect_pads
				(clearance 0)
			)
			(min_thickness 0.25)
			(keepout
				(tracks not_allowed)
				(vias allowed)
				(pads allowed)
				(copperpour not_allowed)
				(footprints allowed)
			)
			(placement
				(enabled no)
				(sheetname "")
			)
			(fill
				(thermal_gap 0.5)
				(thermal_bridge_width 0.5)
				(island_removal_mode 0)
			)
			(polygon
				(pts
					(xy 366.823244 -10.281158) (xy 367.331244 -10.281158) (xy 367.331244 -10.662158) (xy 366.823244 -10.662158)
				)
			)
		)
	)
	(footprint ""
		(layer "F.Cu")
		(at 398.325848 -150.071074)
		(property "Reference" "C8A9"
			(at 0 0 0)
			(layer "F.SilkS")
			(hide yes)
			(effects
				(font
					(size 1.27 1.27)
				)
			)
		)
		(property "Value" ""
			(at 0 0 0)
			(layer "F.Fab")
			(effects
				(font
					(size 1.27 1.27)
				)
			)
		)
		(duplicate_pad_numbers_are_jumpers no)
		(fp_poly
			(pts
				(xy 0.3048 -0.1016) (xy 0.3048 0.9906) (xy -0.3048 0.9906) (xy -0.3048 -0.1016)
			)
			(stroke
				(width 0)
				(type default)
			)
			(fill no)
			(layer "F.CrtYd")
		)
		(fp_line
			(start -0.3048 -0.1016)
			(end -0.3048 0.9906)
			(stroke
				(width 0.1)
				(type default)
			)
			(layer "F.Fab")
		)
		(fp_line
			(start -0.3048 0.9906)
			(end 0.3048 0.9906)
			(stroke
				(width 0.1)
				(type default)
			)
			(layer "F.Fab")
		)
		(fp_line
			(start 0.3048 -0.1016)
			(end -0.3048 -0.1016)
			(stroke
				(width 0.1)
				(type default)
			)
			(layer "F.Fab")
		)
		(fp_line
			(start 0.3048 0.9906)
			(end 0.3048 -0.1016)
			(stroke
				(width 0.1)
				(type default)
			)
			(layer "F.Fab")
		)
		(pad "1" smd rect
			(at 0 0)
			(size 0.508 0.508)
			(layers "F.Cu" "F.Mask" "F.Paste")
			(net "PWRGD_PVNN_PCH_R")
		)
		(pad "2" smd rect
			(at 0 0.889)
			(size 0.508 0.508)
			(layers "F.Cu" "F.Mask" "F.Paste")
			(net "GND")
		)
		(zone
			(layer "F.Cu")
			(hatch none 0.5)
			(connect_pads
				(clearance 0)
			)
			(min_thickness 0.25)
			(keepout
				(tracks allowed)
				(vias not_allowed)
				(pads allowed)
				(copperpour not_allowed)
				(footprints allowed)
			)
			(placement
				(enabled no)
				(sheetname "")
			)
			(fill
				(thermal_gap 0.5)
				(thermal_bridge_width 0.5)
				(island_removal_mode 0)
			)
			(polygon
				(pts
					(xy 398.071848 -149.817074) (xy 398.579848 -149.817074) (xy 398.579848 -149.436074) (xy 398.071848 -149.436074)
				)
			)
		)
		(zone
			(layer "F.Cu")
			(hatch none 0.5)
			(connect_pads
				(clearance 0)
			)
			(min_thickness 0.25)
			(keepout
				(tracks not_allowed)
				(vias allowed)
				(pads allowed)
				(copperpour not_allowed)
				(footprints allowed)
			)
			(placement
				(enabled no)
				(sheetname "")
			)
			(fill
				(thermal_gap 0.5)
				(thermal_bridge_width 0.5)
				(island_removal_mode 0)
			)
			(polygon
				(pts
					(xy 398.071848 -149.436074) (xy 398.579848 -149.436074) (xy 398.579848 -149.817074) (xy 398.071848 -149.817074)
				)
			)
		)
	)
	(footprint ""
		(layer "F.Cu")
		(at 275.7932 -79.6036 180)
		(property "Reference" "C5D23"
			(at 0 0 180)
			(layer "F.SilkS")
			(hide yes)
			(effects
				(font
					(size 1.27 1.27)
				)
			)
		)
		(property "Value" ""
			(at 0 0 180)
			(layer "F.Fab")
			(effects
				(font
					(size 1.27 1.27)
				)
			)
		)
		(duplicate_pad_numbers_are_jumpers no)
		(fp_poly
			(pts
				(xy -0.4953 -0.2032) (xy 0.4953 -0.2032) (xy 0.4953 1.6002) (xy -0.4953 1.6002)
			)
			(stroke
				(width 0)
				(type default)
			)
			(fill no)
			(layer "F.CrtYd")
		)
		(fp_line
			(start 0.4953 1.6002)
			(end -0.4953 1.6002)
			(stroke
				(width 0.1)
				(type default)
			)
			(layer "F.Fab")
		)
		(fp_line
			(start 0.4953 -0.2032)
			(end 0.4953 1.6002)
			(stroke
				(width 0.1)
				(type default)
			)
			(layer "F.Fab")
		)
		(fp_line
			(start -0.4953 1.6002)
			(end -0.4953 -0.2032)
			(stroke
				(width 0.1)
				(type default)
			)
			(layer "F.Fab")
		)
		(fp_line
			(start -0.4953 -0.2032)
			(end 0.4953 -0.2032)
			(stroke
				(width 0.1)
				(type default)
			)
			(layer "F.Fab")
		)
		(pad "1" smd rect
			(at 0 0 180)
			(size 0.762 0.889)
			(layers "F.Cu" "F.Mask" "F.Paste")
			(net "PVCCMCP_CPU0")
		)
		(pad "2" smd rect
			(at 0 1.397 180)
			(size 0.762 0.889)
			(layers "F.Cu" "F.Mask" "F.Paste")
			(net "GND")
		)
		(zone
			(layer "F.Cu")
			(hatch none 0.5)
			(connect_pads
				(clearance 0)
			)
			(min_thickness 0.25)
			(keepout
				(tracks not_allowed)
				(vias allowed)
				(pads allowed)
				(copperpour not_allowed)
				(footprints allowed)
			)
			(placement
				(enabled no)
				(sheetname "")
			)
			(fill
				(thermal_gap 0.5)
				(thermal_bridge_width 0.5)
				(island_removal_mode 0)
			)
			(polygon
				(pts
					(xy 276.1742 -80.0481) (xy 275.4122 -80.0481) (xy 275.4122 -80.5561) (xy 276.1742 -80.5561)
				)
			)
		)
	)
)
